FILE_TYPE = MULTI_PHYS_TABLE;

PART 'Q_FUSE'

{========================================================================================}
:PACK_TYPE | VALUE        | MATERIAL | PART_NUMBER              = ENVCOMP | PART_NUMBER              | JEDEC_TYPE     | CLASS | DESCRIPTION                                    | COMPONENT_TYPE | LEAD_LENGTH | LPID | DAY        ;
{========================================================================================}
 'SMLF'    | '1.1A'       | 'IC'     | 'TMP_QDK110TPU110'(!)    = 'YES'   | 'DK110TPU110'       | 'F1812'      | 'IC'  | '1.1A'                                       | 'CHIP'         | ''          | ''   | ''        
 'SMLF'    | '1.1A'       | 'EMPTY'  | 'TMP_QDK110TPU110'(!)    = 'YES'   | 'DK110TPU110'       | 'F1812'      | 'IO'  | '1.1A'                                       | 'CHIP'         | ''          | ''   | ''        
 'SMLF'    | '4.5A'       | 'IC'     | 'TMP_QDK450WFU004'(!)    = 'YES'   | 'DK450WFU004'       | 'F1206'      | 'IC'  | '4.5A'                                       | 'CHIP'         | ''          | ''   | ''        
 'SMLF'    | '4.5A'       | 'EMPTY'  | 'TMP_QDK450WFU004'(!)    = 'YES'   | 'DK450WFU004'       | 'F1206'      | 'IO'  | '4.5A'                                       | 'CHIP'         | ''          | ''   | ''        
 'SMLF'    | '3A'         | 'IC'     | 'TMP_QDK300UFU000'(!)    = 'YES'   | 'DK300UFU000'       | 'F1206'      | 'IC'  | '3A'                                         | 'CHIP'         | ''          | ''   | ''        
 'SMLF'    | '3A'         | 'EMPTY'  | 'TMP_QDK300UFU000'(!)    = 'YES'   | 'DK300UFU000'       | 'F1206'      | 'IO'  | '3A'                                         | 'CHIP'         | ''          | ''   | ''        
 'SMLF'    | '5A/32V'     | 'IC'     | 'TMP_QDK500WFU011'(!)    = 'YES'   | 'DK500WFU011'       | 'F1206'      | 'IC'  | 'FUSE SMD 5A/ 32V/3216(FAST,UL/CSA)'         | 'CHIP'         | ''          | ''   | ''        
 'SMLF'    | '5A/32V'     | 'EMPTY'  | 'TMP_QDK500WFU011'(!)    = 'YES'   | 'DK500WFU011'       | 'F1206'      | 'IO'  | 'FUSE SMD 5A/ 32V/3216(FAST,UL/CSA)'         | 'CHIP'         | ''          | ''   | ''        
 'SMLF'    | '1.5A/63V'   | 'IC'     | 'TMP-C_S2I_0911_MASON_1'(!) = 'YES'   | 'TMP-C_S2I_0911_MASON_1' | 'F1206'      | 'IC'  | 'FUSE SMD 1.5A 63V FAST(TR/3216FF1.5-R)'     | 'CHIP'         | ''          | ''   | ''        
 'SMLF'    | '1.5A/63V'   | 'EMPTY'  | 'TMP-C_S2I_0911_MASON_1'(!) = 'YES'   | 'TMP-C_S2I_0911_MASON_1' | 'F1206'      | 'IO'  | 'FUSE SMD 1.5A 63V FAST(TR/3216FF1.5-R)'     | 'CHIP'         | ''          | ''   | ''        
 'SMLF'    | '1.6A/9V'    | 'IC'     | 'TMP_QDK160TPU113'(!)    = 'YES'   | 'DK160TPU113'       | 'F1812'      | 'IC'  | 'FUSE SMD 1.6A 9V POLY(MINISMDC160F-2)'      | 'CHIP'         | ''          | ''   | ''        
 'SMLF'    | '1.6A/9V'    | 'EMPTY'  | 'TMP_QDK160TPU113'(!)    = 'YES'   | 'DK160TPU113'       | 'F1812'      | 'IO'  | 'FUSE SMD 1.6A 9V POLY(MINISMDC160F-2)'      | 'CHIP'         | ''          | ''   | ''        
 'SMLF'    | '1.5A/6V'    | 'IC'     | 'QN-DK150TPU030'(!)      = 'YES'   | 'DK150TPU030'         | 'F1206_H56'    | 'IC'  | 'FUSE SMD 1.5A,6V(POLY,NANOSMDC150F-2)'       | 'CHIP'         | ''          | ''   | ''        
 'SMLF'    | '1.5A/6V'    | 'EMPTY'  | 'QN-DK150TPU030'(!)      = 'YES'   | 'DK150TPU030'         | 'F1206_H56'    | 'IO'  | 'FUSE SMD 1.5A,6V(POLY,NANOSMDC150F-2)'       | 'CHIP'         | ''          | ''   | ''        
 'SMLF'    | '3A/6V'      | 'IC'     | 'TMP-C_S2I_0421_MASON_1'(!) = 'YES'   | 'TMP-C_S2I_0421_MASON_1' | 'F2920_3'    | 'IC'  | 'FUSE SMD 3A 6V POLY(SMD300F,UL/CSA)'         | 'CHIP'         | ''          | ''   | ''        
 'SMLF'    | '3A/6V'      | 'EMPTY'  | 'TMP-C_S2I_0421_MASON_1'(!) = 'YES'   | 'TMP-C_S2I_0421_MASON_1' | 'F2920_3'    | 'IO'  | 'FUSE SMD 3A 6V POLY(SMD300F,UL/CSA)'         | 'CHIP'         | ''          | ''   | ''        
 'SMLF'    | '1.5A/6V'    | 'IC'     | 'TMP-C_S2I_0422_MASON_1'(!) = 'YES'   | 'TMP-C_S2I_0422_MASON_1' | 'F1206'      | 'IC'  | 'FUSE SMD 1.5A 6V POLY(nanoSMDC150F,UL/CSA)'  | 'CHIP'         | ''          | ''   | ''        
 'SMLF'    | '1.5A/6V'    | 'EMPTY'  | 'TMP-C_S2I_0422_MASON_1'(!) = 'YES'   | 'TMP-C_S2I_0422_MASON_1' | 'F1206'      | 'IO'  | 'FUSE SMD 1.5A 6V POLY(nanoSMDC150F,UL/CSA)'  | 'CHIP'         | ''          | ''   | ''        
 'SMLF'    | '0.5A/13.2V' | 'IC'     | 'TMP_QDK050SPU017'(!)    = 'YES'   | 'DK050SPU017'       | 'F1206'      | 'IC'  | 'FUSE SMD 0.5A,13.2V(POLY,NANOSMDC050F)'    | 'CHIP'         | ''          | ''   | ''        
 'SMLF'    | '0.5A/13.2V' | 'EMPTY'  | 'TMP_QDK050SPU017'(!)    = 'YES'   | 'DK050SPU017'       | 'F1206'      | 'IO'  | 'FUSE SMD 0.5A,13.2V(POLY,NANOSMDC050F)'    | 'CHIP'         | ''          | ''   | ''        
 'SMLF'    | '3A/15V'     | 'IC'     | 'TMP-C_S2I_0427_MASON_1'(!) = 'YES'   | 'TMP-C_S2I_0427_MASON_1' | 'F2920_1-25' | 'IC'  | 'FUSE SMD 3A 15V POLY(2920L300/15)'          | 'CHIP'         | ''          | ''   | ''        
 'SMLF'    | '3A/15V'     | 'EMPTY'  | 'TMP-C_S2I_0427_MASON_1'(!) = 'YES'   | 'TMP-C_S2I_0427_MASON_1' | 'F2920_1-25' | 'IO'  | 'FUSE SMD 3A 15V POLY(2920L300/15)'          | 'CHIP'         | ''          | ''   | ''        
 'SMLF'    | '1.5A 32V'   | 'IC'     | 'TMP_QDK150WFU000'(!)    = 'YES'   | 'DK150WFU000'       | 'F0603_H19'  | 'IC'  | 'FUSE SMD 1.5A 32V(FAST,UL/CSA,0603)'        | 'CHIP'         | ''          | ''   | ''        
 'SMLF'    | '1.5A 32V'   | 'EMPTY'  | 'TMP_QDK150WFU000'(!)    = 'YES'   | 'DK150WFU000'       | 'F0603_H19'  | 'IO'  | 'FUSE SMD 1.5A 32V(FAST,UL/CSA,0603)'        | 'CHIP'         | ''          | ''   | ''        
 'SMLF'    | '6A,24V'     | 'IC'     | 'TMP_QDK600VPU004'(!)    = 'YES'   | 'DK600VPU004'       | 'F1206'      | 'IC'  | 'FUSE SMD 6A,24V POLY(1206SFS600F/24-2)'     | 'CHIP'         | ''          | ''   | ''        
 'SMLF'    | '6A,24V'     | 'EMPTY'  | 'TMP_QDK600VPU004'(!)    = 'YES'   | 'DK600VPU004'       | 'F1206'      | 'IO'  | 'FUSE SMD 6A,24V POLY(1206SFS600F/24-2)'     | 'CHIP'         | ''          | ''   | ''        
 'SMLF'    | '10A/125V'   | 'IC'     | 'TMP_QDKA00XFU409'(!)    = 'YES'   | 'DKA00XFU409'       | 'F2410'      | 'IC'  | 'FUSE SMD 10A/125V(FAST,UL/CSA)'             | 'CHIP'         | ''          | ''   | ''        
 'SMLF'    | '10A/125V'   | 'EMPTY'  | 'TMP_QDKA00XFU409'(!)    = 'YES'   | 'DKA00XFU409'       | 'F2410'      | 'IO'  | 'FUSE SMD 10A/125V(FAST,UL/CSA)'             | 'CHIP'         | ''          | ''   | ''        
 'SMLF'    | '.75A/13.2V' | 'IC'     | 'DK075SPU002'(!)         = 'YES'   | 'DK075SPU002'            | 'F1812'      | 'IC'  | 'FUSE SMD .75A,13.2V(POLY,MINISMDC075F)LF'    | 'CHIP'         | ''          | ''   | ''        
 'SMLF'    | '.75A/13.2V' | 'EMPTY'  | 'DK075SPU002'(!)         = 'YES'   | 'DK075SPU002'            | 'F1812'      | 'IO'  | 'FUSE SMD .75A,13.2V(POLY,MINISMDC075F)LF'    | 'CHIP'         | ''          | ''   | ''        
 'SMLF'    | '1.1A/16V'   | 'IC'     | 'DK110SPU001'(!)         = 'YES'   | 'DK110SPU001'            | 'F1812'      | 'IC'  | 'FUSE SMD 1.1A 16V POLY(MF-MSMF110/16)'       | 'CHIP'         | ''          | ''   | ''        
 'SMLF'    | '1.1A/16V'   | 'EMPTY'  | 'DK110SPU001'(!)         = 'YES'   | 'DK110SPU001'            | 'F1812'      | 'IO'  | 'FUSE SMD 1.1A 16V POLY(MF-MSMF110/16)'       | 'CHIP'         | ''          | ''   | ''        
 'SMLF'    | '3A/15V'     | 'IC'     | 'DK300SPU002'(!)         = 'YES'   | 'DK300SPU002'            | 'F2920_3'    | 'IC'  | 'FUSE SMD 3A,15V,POLY(SMD300F/15)'            | 'CHIP'         | ''          | ''   | ''        
 'SMLF'    | '3A/15V'     | 'EMPTY'  | 'DK300SPU002'(!)         = 'YES'   | 'DK300SPU002'            | 'F2920_3'    | 'IO'  | 'FUSE SMD 3A,15V,POLY(SMD300F/15)'            | 'CHIP'         | ''          | ''   | ''        
 'SMLF'    | '1.1A/8V'    | 'IC'     | 'DK110TPU012'(!)         = 'YES'   | 'DK110TPU012'            | 'F1812'      | 'IC'  | 'FUSE SMD 1.1A,8V(POLY,MINISMDC110F-2)'       | 'CHIP'         | ''          | ''   | '20101005'
 'SMLF'    | '1.1A/8V'    | 'EMPTY'  | 'DK110TPU012'(!)         = 'YES'   | 'DK110TPU012'            | 'F1812'      | 'IO'  | 'FUSE SMD 1.1A,8V(POLY,MINISMDC110F-2)'       | 'CHIP'         | ''          | ''   | '20101005'
 'SMLF'    | '1.5A/6V'    | 'IC'     | 'DK150TPU072'(!)         = 'YES'   | 'DK150TPU072'            | 'F1206'      | 'IC'  | 'FUSE SMD 1.5A,6V(POLY,1206L150PR)'           | 'CHIP'         | ''          | ''   | '20110207'
 'SMLF'    | '1.5A/6V'    | 'EMPTY'  | 'DK150TPU072'(!)         = 'YES'   | 'DK150TPU072'            | 'F1206'      | 'IO'  | 'FUSE SMD 1.5A,6V(POLY,1206L150PR)'           | 'CHIP'         | ''          | ''   | '20110207'
 'SMLF'    | '1.1A/6V'    | 'IC'     | 'DK110TPU501'(!)         = 'YES'   | 'DK110TPU501'            | 'F1206'      | 'IC'  | 'FUSE SMD 1.1A6V POLY(NANOSMDC110F-2)1206'    | 'CHIP'         | ''          | ''   | '20110217'
 'SMLF'    | '1.1A/6V'    | 'EMPTY'  | 'DK110TPU501'(!)         = 'YES'   | 'DK110TPU501'            | 'F1206'      | 'IO'  | 'FUSE SMD 1.1A6V POLY(NANOSMDC110F-2)1206'    | 'CHIP'         | ''          | ''   | '20110217'
 'SMLF'    | '5A/125V'    | 'IC'     | 'DK500XFU001'(!)         = 'YES'   | 'DK500XFU001'            | 'F2410'      | 'IC'  | 'FUSE SMD 5A/125V(FAST,UL/CSA)0451005.MRL'    | 'CHIP'         | ''          | ''   | '20120224'
 'SMLF'    | '5A/125V'    | 'EMPTY'  | 'DK500XFU001'(!)         = 'YES'   | 'DK500XFU001'            | 'F2410'      | 'IO'  | 'FUSE SMD 5A/125V(FAST,UL/CSA)0451005.MRL'    | 'CHIP'         | ''          | ''   | '20120224'
 'SMLF'    | '3A/15V'     | 'IC'     | 'DK300SPU000'(!)         = 'YES'   | 'DK300SPU000'            | 'F2920_1-25' | 'IC'  | 'FUSE SMD 3A 15V POLY(2920L300/15DR)'         | 'CHIP'         | ''          | ''   | '20120306'
 'SMLF'    | '3A/15V'     | 'EMPTY'  | 'DK300SPU000'(!)         = 'YES'   | 'DK300SPU000'            | 'F2920_1-25' | 'IO'  | 'FUSE SMD 3A 15V POLY(2920L300/15DR)'         | 'CHIP'         | ''          | ''   | '20120306'
 'SMLF'    | '15A/125V'   | 'IC'     | 'DKF00VFU004'(!) = 'YES'   | 'DKF00VFU004'  | 'F2410'      | 'IC'  | 'FUSE SMD 15A/125V(FAST,UL/CSA)SSQ 15'       | 'CHIP'         | ''          | ''   | '20120309'
 'SMLF'    | '15A/125V'   | 'EMPTY'  | 'DKF00VFU004'(!) = 'YES'   | 'DKF00VFU004'  | 'F2410'      | 'IO'  | 'FUSE SMD 15A/125V(FAST,UL/CSA)SSQ 15'       | 'CHIP'         | ''          | ''   | '20120309'
 'SMLF'     | '1.5A/125V'  | 'IC'     | 'DK150XFU000'(!)           = 'YES'   | 'DK150XFU000'              | 'F2410'           | 'IC'  | 'FUSE SMD 1.5A/125V(FAST,UL/CSA/CE)SSQ1.5'    | 'CHIP'         | ''          | ''   | '20120406'
 'SMLF'     | '1.5A/125V'  | 'EMPTY'  | 'DK150XFU000'(!)           = 'YES'   | 'DK150XFU000'              | 'F2410'           | 'IO'  | 'FUSE SMD 1.5A/125V(FAST,UL/CSA/CE)SSQ1.5'    | 'CHIP'         | ''          | ''   | '20120406'
 'SMLF'     | '2A/6V'      | 'IC'     | 'DK200TPU004'(!)           = 'YES'   | 'DK200TPU004'              | 'F1206'           | 'IC'  | 'FUSE SMD 2A 6V(POLY,UL/CSA,1206)'           | 'CHIP'         | ''          | ''   | '20120421'
 'SMLF'     | '2A/6V'      | 'EMPTY'  | 'DK200TPU004'(!)           = 'YES'   | 'DK200TPU004'              | 'F1206'           | 'IO'  | 'FUSE SMD 2A 6V(POLY,UL/CSA,1206)'           | 'CHIP'         | ''          | ''   | '20120421'
 'THLF'    | '9A/16V'     | 'IC'     | 'DK900SPU001'(!) = 'YES'   | 'DK900SPU001'    | 'F1255_16R900GMR'   | 'IC'  | 'FUSE DIP 9A/16V (POLY,UL/TUV)16R900GMR'     | 'CHIP'         | ''          | ''   | '20120314'
 'THLF'    | '9A/16V'     | 'EMPTY'  | 'DK900SPU001'(!) = 'YES'   | 'DK900SPU001'    | 'F1255_16R900GMR'   | 'IO'  | 'FUSE DIP 9A/16V (POLY,UL/TUV)16R900GMR'     | 'CHIP'         | ''          | ''   | '20120314'
 'THLF'    | '14A/16V'    | 'IC'     | 'DKE00SPU000'(!) = 'YES'   | 'DKE00SPU000'    | 'F9314_16R1400GH'   | 'IC'  | 'FUSE DIP 14A/16V(POLY,UL/TUV)16R1400GH'     | 'CHIP'         | ''          | ''   | '20120314'
 'THLF'    | '14A/16V'    | 'EMPTY'  | 'DKE00SPU000'(!) = 'YES'   | 'DKE00SPU000'    | 'F9314_16R1400GH'   | 'IO'  | 'FUSE DIP 14A/16V(POLY,UL/TUV)16R1400GH'     | 'CHIP'         | ''          | ''   | '20120314'
 'THLF_SEL'    | '9A/16V'     | 'IC'     | 'SP_DK900SPU001'(!) = 'YES'   | 'DK900SPU001' | 'G_F1255_16R900GMR' | 'IC'  | 'FUSE DIP 9A/16V (POLY,UL/TUV)16R900GMR'     | 'CHIP'         | ''          | ''   | '20120314'
 'THLF_SEL'    | '9A/16V'     | 'EMPTY'  | 'SP_DK900SPU001'(!) = 'YES'   | 'DK900SPU001' | 'G_F1255_16R900GMR' | 'IO'  | 'FUSE DIP 9A/16V (POLY,UL/TUV)16R900GMR'     | 'CHIP'         | ''          | ''   | '20120314'
 'THLF_SEL'    | '14A/16V'    | 'IC'     | 'SP_DKE00SPU000'(!) = 'YES'   | 'DKE00SPU000' | 'G_F9314_16R1400GH' | 'IC'  | 'FUSE DIP 14A/16V(POLY,UL/TUV)16R1400GH'     | 'CHIP'         | ''          | ''   | '20120314'
 'THLF_SEL'    | '14A/16V'    | 'EMPTY'  | 'SP_DKE00SPU000'(!) = 'YES'   | 'DKE00SPU000' | 'G_F9314_16R1400GH' | 'IO'  | 'FUSE DIP 14A/16V(POLY,UL/TUV)16R1400GH'     | 'CHIP'         | ''          | ''   | '20120314'
 'SMLF'     | '0.5A'       | 'IC'     | 'DK050SPU033'(!)         = 'YES'   | 'DK050SPU033'            | 'F1812'           | 'IC'  | 'FUSE SMD 0.5A 15V POLY(SMD1812P050TF)'      | 'CHIP'         | ''          | ''   | '20120525'
 'SMLF'     | '0.5A'       | 'EMPTY'  | 'DK050SPU033'(!)         = 'YES'   | 'DK050SPU033'            | 'F1812'           | 'IO'  | 'FUSE SMD 0.5A 15V POLY(SMD1812P050TF)'      | 'CHIP'         | ''          | ''   | '20120525'
 'SMLF'     | '2.6A'       | 'IC'     | 'DK260TPU001'(!)         = 'YES'   | 'DK260TPU001'            | 'F1812'           | 'IC'  | 'FUSE SMD 2.6A,6V(POLY,MINISMDC260F)'        | 'CHIP'         | ''          | ''   | '20120627'
 'SMLF'     | '2.6A'       | 'EMPTY'  | 'DK260TPU001'(!)         = 'YES'   | 'DK260TPU001'            | 'F1812'           | 'IO'  | 'FUSE SMD 2.6A,6V(POLY,MINISMDC260F)'        | 'CHIP'         | ''          | ''   | '20120627'
 'SMLF'     | '8A/32V'     | 'IC'     | 'DK800WFU000'(!)         = 'YES'   | 'DK800WFU000'            | 'F1206'             | 'IC'  | 'FUSE SMD 8A 32V(FAST,0437008.WR,1206)'       | 'CHIP'         | ''          | ''   | '20120628'
 'SMLF'     | '8A/32V'     | 'EMPTY'  | 'DK800WFU000'(!)         = 'YES'   | 'DK800WFU000'            | 'F1206'             | 'IO'  | 'FUSE SMD 8A 32V(FAST,0437008.WR,1206)'       | 'CHIP'         | ''          | ''   | '20120628'
 'SMLF'     | '3A/24V'     | 'IC'     | 'DK300VPU000'(!)         = 'YES'   | 'DK300VPU000'            | 'F2920_1-6'       | 'IC'  | 'FUSE SMD 3A 24V POLY(MF-LSMF300/24X-2)'      | 'CHIP'         | ''          | ''   | '20120706'
 'SMLF'     | '3A/24V'     | 'EMPTY'  | 'DK300VPU000'(!)         = 'YES'   | 'DK300VPU000'            | 'F2920_1-6'       | 'IO'  | 'FUSE SMD 3A 24V POLY(MF-LSMF300/24X-2)'      | 'CHIP'         | ''          | ''   | '20120706'
 'SMLF'     | '0.35A/6V'   | 'IC'     | 'DK035TPU000'(!)         = ''       | 'DK035TPU000'            | 'F0603_H62'       | 'IC'  | 'FUSE SMD 0.35A.6V(POLY.SMD0603P035TF)'           | ''          | ''   | '20120914'
 'SMLF'     | '0.35A/6V'   | 'EMPTY'  | 'DK035TPU000'(!)         = ''       | 'DK035TPU000'            | 'F0603_H62'       | 'IO'  | 'FUSE SMD 0.35A.6V(POLY.SMD0603P035TF)'           | ''          | ''   | '20120914'

END_PART

END.

